# SCM (Grand Teton) — schematic netlist excerpt (pin names and nets, part order shuffled) for the footprints in the layout excerpt that follows; sources: Cadence DE-HDL packaged netlist, KiCad conversion of 12092022_DA0F0TMDCD0_F0T_Management_Board_D_brd_V3_OCP.brd

R269  Q_RES  4.7K 1% CHIP  pkg 0402LF  page 27 : A = P3V3_AUX ; B = SMB_BMC_ALERT4_N
C336  Q_CAP  0.1UF 25V 10% X7R  pkg 0402  page 50 : A = P3V3_AUX ; B = GND

(kicad_pcb
	(version 20260206)
	(generator "pcbnew")
	(generator_version "10.0")
	(general
		(thickness 1.6)
		(legacy_teardrops no)
	)
	(paper "A4")
	(title_block
		(title "12092022_DA0F0TMDCD0_F0T_Management_Board_D_brd_V3_OCP.brd")
		(comment 1 "Grand Teton / footprints 582-583 of 1440")
	)
	(layers
		(0 "F.Cu" signal "TOP")
		(4 "In1.Cu" signal "GND")
		(6 "In2.Cu" signal "IN1")
		(8 "In3.Cu" signal "GND1")
		(10 "In4.Cu" signal "IN2")
		(12 "In5.Cu" signal "VCC")
		(14 "In6.Cu" signal "VCC1")
		(16 "In7.Cu" signal "IN3")
		(18 "In8.Cu" signal "GND2")
		(20 "In9.Cu" signal "IN4")
		(22 "In10.Cu" signal "GND3")
		(2 "B.Cu" signal "BOTTOM")
		(9 "F.Adhes" user "F.Adhesive")
		(11 "B.Adhes" user "B.Adhesive")
		(13 "F.Paste" user "Package Geometry/Pastemask Top")
		(15 "B.Paste" user "Package Geometry/Pastemask Bottom")
		(5 "F.SilkS" user "Ref Des/Silkscreen Top")
		(7 "B.SilkS" user "Ref Des/Silkscreen Bottom")
		(1 "F.Mask" user "Board Geometry/Soldermask Top")
		(3 "B.Mask" user "Board Geometry/Soldermask Bottom")
		(17 "Dwgs.User" user "User.Drawings")
		(19 "Cmts.User" user "User.Comments")
		(21 "Eco1.User" user "User.Eco1")
		(23 "Eco2.User" user "User.Eco2")
		(25 "Edge.Cuts" user "Board Geometry/Outline")
		(27 "Margin" user)
		(31 "F.CrtYd" user "Package Geometry/Place Bound Top")
		(29 "B.CrtYd" user "Package Geometry/Place Bound Bottom")
		(35 "F.Fab" user "Ref Des/Assembly Top")
		(33 "B.Fab" user "Ref Des/Assembly Bottom")
	)
	(footprint ""
		(layer "F.Cu")
		(at 37.68598 -44.1325 -90)
		(property "Reference" "R269"
			(at 0 0 270)
			(layer "F.SilkS")
			(hide yes)
			(effects
				(font
					(size 1.27 1.27)
				)
			)
		)
		(property "Value" ""
			(at 0 0 270)
			(layer "F.Fab")
			(effects
				(font
					(size 1.27 1.27)
				)
			)
		)
		(duplicate_pad_numbers_are_jumpers no)
		(fp_line
			(start -0.7874 0.4064)
			(end -0.7874 -0.4064)
			(stroke
				(width 0.1524)
				(type default)
			)
			(layer "F.SilkS")
		)
		(fp_line
			(start 0.7874 0.4064)
			(end -0.7874 0.4064)
			(stroke
				(width 0.1524)
				(type default)
			)
			(layer "F.SilkS")
		)
		(fp_line
			(start -0.7874 -0.4064)
			(end 0.7874 -0.4064)
			(stroke
				(width 0.1524)
				(type default)
			)
			(layer "F.SilkS")
		)
		(fp_line
			(start 0.7874 -0.4064)
			(end 0.7874 0.4064)
			(stroke
				(width 0.1524)
				(type default)
			)
			(layer "F.SilkS")
		)
		(fp_line
			(start -0.67945 0.3048)
			(end -0.67945 -0.305054)
			(stroke
				(width 0.1)
				(type default)
			)
			(layer "F.Fab")
		)
		(fp_line
			(start -0.12065 0.3048)
			(end -0.67945 0.3048)
			(stroke
				(width 0.1)
				(type default)
			)
			(layer "F.Fab")
		)
		(fp_line
			(start 0.120396 0.3048)
			(end 0.120396 0.2794)
			(stroke
				(width 0.1)
				(type default)
			)
			(layer "F.Fab")
		)
		(fp_line
			(start 0.67945 0.3048)
			(end 0.120396 0.3048)
			(stroke
				(width 0.1)
				(type default)
			)
			(layer "F.Fab")
		)
		(fp_line
			(start -0.12065 0.2794)
			(end -0.12065 0.3048)
			(stroke
				(width 0.1)
				(type default)
			)
			(layer "F.Fab")
		)
		(fp_line
			(start 0.120396 0.2794)
			(end -0.12065 0.2794)
			(stroke
				(width 0.1)
				(type default)
			)
			(layer "F.Fab")
		)
		(fp_line
			(start -0.12065 -0.2794)
			(end 0.12065 -0.2794)
			(stroke
				(width 0.1)
				(type default)
			)
			(layer "F.Fab")
		)
		(fp_line
			(start 0.12065 -0.2794)
			(end 0.12065 -0.3048)
			(stroke
				(width 0.1)
				(type default)
			)
			(layer "F.Fab")
		)
		(fp_line
			(start 0.12065 -0.3048)
			(end 0.67945 -0.3048)
			(stroke
				(width 0.1)
				(type default)
			)
			(layer "F.Fab")
		)
		(fp_line
			(start 0.67945 -0.3048)
			(end 0.67945 0.3048)
			(stroke
				(width 0.1)
				(type default)
			)
			(layer "F.Fab")
		)
		(fp_line
			(start -0.67945 -0.305054)
			(end -0.12065 -0.305054)
			(stroke
				(width 0.1)
				(type default)
			)
			(layer "F.Fab")
		)
		(fp_line
			(start -0.12065 -0.305054)
			(end -0.12065 -0.2794)
			(stroke
				(width 0.1)
				(type default)
			)
			(layer "F.Fab")
		)
		(pad "1" smd circle
			(at -0.40005 0 270)
			(size 0 0)
			(layers "F.Cu" "F.Mask" "F.Paste")
			(net "P3V3_AUX")
		)
		(pad "2" smd circle
			(at 0.40005 0 270)
			(size 0 0)
			(layers "F.Cu" "F.Mask" "F.Paste")
			(net "SMB_BMC_ALERT4_N")
		)
	)
	(footprint ""
		(layer "F.Cu")
		(at 70.358 -11.684 -90)
		(property "Reference" "C336"
			(at 0 0 270)
			(layer "F.SilkS")
			(hide yes)
			(effects
				(font
					(size 1.27 1.27)
				)
			)
		)
		(property "Value" ""
			(at 0 0 270)
			(layer "F.Fab")
			(effects
				(font
					(size 1.27 1.27)
				)
			)
		)
		(duplicate_pad_numbers_are_jumpers no)
		(fp_line
			(start -0.7874 0.4064)
			(end -0.7874 -0.4064)
			(stroke
				(width 0.1524)
				(type default)
			)
			(layer "F.SilkS")
		)
		(fp_line
			(start 0.7874 0.4064)
			(end -0.7874 0.4064)
			(stroke
				(width 0.1524)
				(type default)
			)
			(layer "F.SilkS")
		)
		(fp_line
			(start -0.7874 -0.4064)
			(end 0.7874 -0.4064)
			(stroke
				(width 0.1524)
				(type default)
			)
			(layer "F.SilkS")
		)
		(fp_line
			(start 0.7874 -0.4064)
			(end 0.7874 0.4064)
			(stroke
				(width 0.1524)
				(type default)
			)
			(layer "F.SilkS")
		)
		(fp_line
			(start -0.67945 0.3048)
			(end -0.67945 -0.305054)
			(stroke
				(width 0.1)
				(type default)
			)
			(layer "F.Fab")
		)
		(fp_line
			(start -0.12065 0.3048)
			(end -0.67945 0.3048)
			(stroke
				(width 0.1)
				(type default)
			)
			(layer "F.Fab")
		)
		(fp_line
			(start 0.120396 0.3048)
			(end 0.120396 0.2794)
			(stroke
				(width 0.1)
				(type default)
			)
			(layer "F.Fab")
		)
		(fp_line
			(start 0.67945 0.3048)
			(end 0.120396 0.3048)
			(stroke
				(width 0.1)
				(type default)
			)
			(layer "F.Fab")
		)
		(fp_line
			(start -0.12065 0.2794)
			(end -0.12065 0.3048)
			(stroke
				(width 0.1)
				(type default)
			)
			(layer "F.Fab")
		)
		(fp_line
			(start 0.120396 0.2794)
			(end -0.12065 0.2794)
			(stroke
				(width 0.1)
				(type default)
			)
			(layer "F.Fab")
		)
		(fp_line
			(start -0.12065 -0.2794)
			(end 0.12065 -0.2794)
			(stroke
				(width 0.1)
				(type default)
			)
			(layer "F.Fab")
		)
		(fp_line
			(start 0.12065 -0.2794)
			(end 0.12065 -0.3048)
			(stroke
				(width 0.1)
				(type default)
			)
			(layer "F.Fab")
		)
		(fp_line
			(start 0.12065 -0.3048)
			(end 0.67945 -0.3048)
			(stroke
				(width 0.1)
				(type default)
			)
			(layer "F.Fab")
		)
		(fp_line
			(start 0.67945 -0.3048)
			(end 0.67945 0.3048)
			(stroke
				(width 0.1)
				(type default)
			)
			(layer "F.Fab")
		)
		(fp_line
			(start -0.67945 -0.305054)
			(end -0.12065 -0.305054)
			(stroke
				(width 0.1)
				(type default)
			)
			(layer "F.Fab")
		)
		(fp_line
			(start -0.12065 -0.305054)
			(end -0.12065 -0.2794)
			(stroke
				(width 0.1)
				(type default)
			)
			(layer "F.Fab")
		)
		(pad "1" smd circle
			(at -0.40005 0 270)
			(size 0 0)
			(layers "F.Cu" "F.Mask" "F.Paste")
			(net "P3V3_AUX")
		)
		(pad "2" smd circle
			(at 0.40005 0 270)
			(size 0 0)
			(layers "F.Cu" "F.Mask" "F.Paste")
			(net "GND")
		)
	)
)
